(kicad_pcb
	(version 20260206)
	(generator "pcbnew")
	(generator_version "10.0")
	(general
		(thickness 1.6)
		(legacy_teardrops no)
	)
	(paper "A4")
	(title_block
		(title "Bryce Canyon_R.DPB_16317-1_OCP.brd")
		(comment 1 "Bryce Canyon / footprints 1646-1652 of 2099")
	)
	(layers
		(0 "F.Cu" signal "TOP")
		(4 "In1.Cu" signal "L2GND")
		(6 "In2.Cu" signal "L3")
		(8 "In3.Cu" signal "L4VCC")
		(10 "In4.Cu" signal "L5VCC")
		(12 "In5.Cu" signal "L6")
		(14 "In6.Cu" signal "L7GND")
		(2 "B.Cu" signal "BOTTOM")
		(9 "F.Adhes" user "F.Adhesive")
		(11 "B.Adhes" user "B.Adhesive")
		(13 "F.Paste" user "Package Geometry/Pastemask Top")
		(15 "B.Paste" user "Package Geometry/Pastemask Bottom")
		(5 "F.SilkS" user "Ref Des/Silkscreen Top")
		(7 "B.SilkS" user "Ref Des/Silkscreen Bottom")
		(1 "F.Mask" user "Board Geometry/Soldermask Top")
		(3 "B.Mask" user "Board Geometry/Soldermask Bottom")
		(17 "Dwgs.User" user "User.Drawings")
		(19 "Cmts.User" user "User.Comments")
		(21 "Eco1.User" user "User.Eco1")
		(23 "Eco2.User" user "User.Eco2")
		(25 "Edge.Cuts" user "Board Geometry/Outline")
		(27 "Margin" user)
		(31 "F.CrtYd" user "Package Geometry/Place Bound Top")
		(29 "B.CrtYd" user "Package Geometry/Place Bound Bottom")
		(35 "F.Fab" user "Ref Des/Assembly Top")
		(33 "B.Fab" user "Ref Des/Assembly Bottom")
	)
	(footprint ""
		(layer "F.Cu")
		(at 244.37848 -195.58254 90)
		(property "Reference" "R72"
			(at 0 0 90)
			(layer "F.SilkS")
			(hide yes)
			(effects
				(font
					(size 1.27 1.27)
				)
			)
		)
		(property "Value" "4K7R2F-GP"
			(at 0.064008 -3.993896 90)
			(unlocked yes)
			(layer "F.Fab")
			(hide yes)
			(effects
				(font
					(size 1.016 1.016)
					(thickness 0.1524)
				)
			)
		)
		(property "Device Type" "R402H16"
			(at 0.064008 -5.517896 90)
			(unlocked yes)
			(layer "F.Fab")
			(hide yes)
			(effects
				(font
					(size 1.016 1.016)
					(thickness 0.1524)
				)
			)
		)
		(duplicate_pad_numbers_are_jumpers no)
		(fp_line
			(start 0.508 -0.9398)
			(end -0.508 -0.9398)
			(stroke
				(width 0.1524)
				(type default)
			)
			(layer "F.SilkS")
		)
		(fp_line
			(start -0.508 -0.9398)
			(end -0.508 0.9398)
			(stroke
				(width 0.1524)
				(type default)
			)
			(layer "F.SilkS")
		)
		(fp_rect
			(start -0.508 0.9398)
			(end 0.508 -0.9398)
			(stroke
				(width 0)
				(type default)
			)
			(fill no)
			(layer "F.CrtYd")
		)
		(fp_rect
			(start -0.508 0.9398)
			(end 0.508 -0.9398)
			(stroke
				(width 0)
				(type default)
			)
			(fill no)
			(layer "F.Fab")
		)
		(pad "1" smd custom
			(at 0 -0.4445 90)
			(size 0.1397 0.1397)
			(layers "F.Cu" "F.Mask" "F.Paste")
			(net "IO_EXP2_A1")
			(options
				(clearance outline)
				(anchor circle)
			)
			(primitives
				(gr_poly
					(pts
						(arc
							(start -0.1778 -0.2794)
							(mid -0.249642 -0.249642)
							(end -0.2794 -0.1778)
						)
						(arc
							(start -0.2794 0.1778)
							(mid -0.249642 0.249642)
							(end -0.1778 0.2794)
						)
						(arc
							(start 0.1778 0.2794)
							(mid 0.249642 0.249642)
							(end 0.2794 0.1778)
						)
						(arc
							(start 0.2794 -0.1778)
							(mid 0.249642 -0.249642)
							(end 0.1778 -0.2794)
						)
					)
					(width 0)
					(fill yes)
				)
			)
		)
		(pad "2" smd custom
			(at 0 0.4445 90)
			(size 0.1397 0.1397)
			(layers "F.Cu" "F.Mask" "F.Paste")
			(net "GND")
			(options
				(clearance outline)
				(anchor circle)
			)
			(primitives
				(gr_poly
					(pts
						(arc
							(start -0.1778 -0.2794)
							(mid -0.249642 -0.249642)
							(end -0.2794 -0.1778)
						)
						(arc
							(start -0.2794 0.1778)
							(mid -0.249642 0.249642)
							(end -0.1778 0.2794)
						)
						(arc
							(start 0.1778 0.2794)
							(mid 0.249642 0.249642)
							(end 0.2794 0.1778)
						)
						(arc
							(start 0.2794 -0.1778)
							(mid 0.249642 -0.249642)
							(end 0.1778 -0.2794)
						)
					)
					(width 0)
					(fill yes)
				)
			)
		)
	)
	(footprint ""
		(layer "F.Cu")
		(at 221.996 -221.996 90)
		(property "Reference" "R23"
			(at 0 0 90)
			(layer "F.SilkS")
			(hide yes)
			(effects
				(font
					(size 1.27 1.27)
				)
			)
		)
		(property "Value" "4K7R2F-GP"
			(at 0.064008 -3.993896 90)
			(unlocked yes)
			(layer "F.Fab")
			(hide yes)
			(effects
				(font
					(size 1.016 1.016)
					(thickness 0.1524)
				)
			)
		)
		(property "Device Type" "R402H16"
			(at 0.064008 -5.517896 90)
			(unlocked yes)
			(layer "F.Fab")
			(hide yes)
			(effects
				(font
					(size 1.016 1.016)
					(thickness 0.1524)
				)
			)
		)
		(duplicate_pad_numbers_are_jumpers no)
		(fp_line
			(start 0.508 -0.9398)
			(end -0.508 -0.9398)
			(stroke
				(width 0.1524)
				(type default)
			)
			(layer "F.SilkS")
		)
		(fp_line
			(start -0.508 -0.9398)
			(end -0.508 0.9398)
			(stroke
				(width 0.1524)
				(type default)
			)
			(layer "F.SilkS")
		)
		(fp_rect
			(start -0.508 0.9398)
			(end 0.508 -0.9398)
			(stroke
				(width 0)
				(type default)
			)
			(fill no)
			(layer "F.CrtYd")
		)
		(fp_rect
			(start -0.508 0.9398)
			(end 0.508 -0.9398)
			(stroke
				(width 0)
				(type default)
			)
			(fill no)
			(layer "F.Fab")
		)
		(pad "1" smd custom
			(at 0 -0.4445 90)
			(size 0.1397 0.1397)
			(layers "F.Cu" "F.Mask" "F.Paste")
			(net "IO_EXP1_HDD_FAULT_A0")
			(options
				(clearance outline)
				(anchor circle)
			)
			(primitives
				(gr_poly
					(pts
						(arc
							(start -0.1778 -0.2794)
							(mid -0.249642 -0.249642)
							(end -0.2794 -0.1778)
						)
						(arc
							(start -0.2794 0.1778)
							(mid -0.249642 0.249642)
							(end -0.1778 0.2794)
						)
						(arc
							(start 0.1778 0.2794)
							(mid 0.249642 0.249642)
							(end 0.2794 0.1778)
						)
						(arc
							(start 0.2794 -0.1778)
							(mid 0.249642 -0.249642)
							(end 0.1778 -0.2794)
						)
					)
					(width 0)
					(fill yes)
				)
			)
		)
		(pad "2" smd custom
			(at 0 0.4445 90)
			(size 0.1397 0.1397)
			(layers "F.Cu" "F.Mask" "F.Paste")
			(net "GND")
			(options
				(clearance outline)
				(anchor circle)
			)
			(primitives
				(gr_poly
					(pts
						(arc
							(start -0.1778 -0.2794)
							(mid -0.249642 -0.249642)
							(end -0.2794 -0.1778)
						)
						(arc
							(start -0.2794 0.1778)
							(mid -0.249642 0.249642)
							(end -0.1778 0.2794)
						)
						(arc
							(start 0.1778 0.2794)
							(mid 0.249642 0.249642)
							(end 0.2794 0.1778)
						)
						(arc
							(start 0.2794 -0.1778)
							(mid 0.249642 -0.249642)
							(end 0.1778 -0.2794)
						)
					)
					(width 0)
					(fill yes)
				)
			)
		)
	)
	(footprint ""
		(layer "F.Cu")
		(at 363.1184 -134.5946 90)
		(property "Reference" "R514"
			(at 0 0 90)
			(layer "F.SilkS")
			(hide yes)
			(effects
				(font
					(size 1.27 1.27)
				)
			)
		)
		(property "Value" "4K7R2J-2-GP"
			(at 0.064008 -3.993896 90)
			(unlocked yes)
			(layer "F.Fab")
			(hide yes)
			(effects
				(font
					(size 1.016 1.016)
					(thickness 0.1524)
				)
			)
		)
		(property "Device Type" "R402H16"
			(at 0.064008 -5.517896 90)
			(unlocked yes)
			(layer "F.Fab")
			(hide yes)
			(effects
				(font
					(size 1.016 1.016)
					(thickness 0.1524)
				)
			)
		)
		(duplicate_pad_numbers_are_jumpers no)
		(fp_line
			(start 0.508 -0.9398)
			(end -0.508 -0.9398)
			(stroke
				(width 0.1524)
				(type default)
			)
			(layer "F.SilkS")
		)
		(fp_line
			(start -0.508 -0.9398)
			(end -0.508 0.9398)
			(stroke
				(width 0.1524)
				(type default)
			)
			(layer "F.SilkS")
		)
		(fp_rect
			(start -0.508 0.9398)
			(end 0.508 -0.9398)
			(stroke
				(width 0)
				(type default)
			)
			(fill no)
			(layer "F.CrtYd")
		)
		(fp_rect
			(start -0.508 0.9398)
			(end 0.508 -0.9398)
			(stroke
				(width 0)
				(type default)
			)
			(fill no)
			(layer "F.Fab")
		)
		(pad "1" smd custom
			(at 0 -0.4445 90)
			(size 0.1397 0.1397)
			(layers "F.Cu" "F.Mask" "F.Paste")
			(net "P12V_B")
			(options
				(clearance outline)
				(anchor circle)
			)
			(primitives
				(gr_poly
					(pts
						(arc
							(start -0.1778 -0.2794)
							(mid -0.249642 -0.249642)
							(end -0.2794 -0.1778)
						)
						(arc
							(start -0.2794 0.1778)
							(mid -0.249642 0.249642)
							(end -0.1778 0.2794)
						)
						(arc
							(start 0.1778 0.2794)
							(mid 0.249642 0.249642)
							(end 0.2794 0.1778)
						)
						(arc
							(start 0.2794 -0.1778)
							(mid 0.249642 -0.249642)
							(end 0.1778 -0.2794)
						)
					)
					(width 0)
					(fill yes)
				)
			)
		)
		(pad "2" smd custom
			(at 0 0.4445 90)
			(size 0.1397 0.1397)
			(layers "F.Cu" "F.Mask" "F.Paste")
			(net "SW_HDD_P19")
			(options
				(clearance outline)
				(anchor circle)
			)
			(primitives
				(gr_poly
					(pts
						(arc
							(start -0.1778 -0.2794)
							(mid -0.249642 -0.249642)
							(end -0.2794 -0.1778)
						)
						(arc
							(start -0.2794 0.1778)
							(mid -0.249642 0.249642)
							(end -0.1778 0.2794)
						)
						(arc
							(start 0.1778 0.2794)
							(mid 0.249642 0.249642)
							(end 0.2794 0.1778)
						)
						(arc
							(start 0.2794 -0.1778)
							(mid 0.249642 -0.249642)
							(end 0.1778 -0.2794)
						)
					)
					(width 0)
					(fill yes)
				)
			)
		)
	)
	(footprint ""
		(layer "F.Cu")
		(at 364.236 -19.558 -90)
		(property "Reference" "R790"
			(at 0 0 270)
			(layer "F.SilkS")
			(hide yes)
			(effects
				(font
					(size 1.27 1.27)
				)
			)
		)
		(property "Value" "4K7R2J-2-GP"
			(at 0.064008 -3.993896 270)
			(unlocked yes)
			(layer "F.Fab")
			(hide yes)
			(effects
				(font
					(size 1.016 1.016)
					(thickness 0.1524)
				)
			)
		)
		(property "Device Type" "R402H16"
			(at 0.064008 -5.517896 270)
			(unlocked yes)
			(layer "F.Fab")
			(hide yes)
			(effects
				(font
					(size 1.016 1.016)
					(thickness 0.1524)
				)
			)
		)
		(duplicate_pad_numbers_are_jumpers no)
		(fp_line
			(start -0.508 -0.9398)
			(end -0.508 0.9398)
			(stroke
				(width 0.1524)
				(type default)
			)
			(layer "F.SilkS")
		)
		(fp_line
			(start 0.508 -0.9398)
			(end -0.508 -0.9398)
			(stroke
				(width 0.1524)
				(type default)
			)
			(layer "F.SilkS")
		)
		(fp_rect
			(start -0.508 0.9398)
			(end 0.508 -0.9398)
			(stroke
				(width 0)
				(type default)
			)
			(fill no)
			(layer "F.CrtYd")
		)
		(fp_rect
			(start -0.508 0.9398)
			(end 0.508 -0.9398)
			(stroke
				(width 0)
				(type default)
			)
			(fill no)
			(layer "F.Fab")
		)
		(pad "1" smd custom
			(at 0 -0.4445 270)
			(size 0.1397 0.1397)
			(layers "F.Cu" "F.Mask" "F.Paste")
			(net "P12V_B")
			(options
				(clearance outline)
				(anchor circle)
			)
			(primitives
				(gr_poly
					(pts
						(arc
							(start -0.1778 -0.2794)
							(mid -0.249642 -0.249642)
							(end -0.2794 -0.1778)
						)
						(arc
							(start -0.2794 0.1778)
							(mid -0.249642 0.249642)
							(end -0.1778 0.2794)
						)
						(arc
							(start 0.1778 0.2794)
							(mid 0.249642 0.249642)
							(end 0.2794 0.1778)
						)
						(arc
							(start 0.2794 -0.1778)
							(mid 0.249642 -0.249642)
							(end 0.1778 -0.2794)
						)
					)
					(width 0)
					(fill yes)
				)
			)
		)
		(pad "2" smd custom
			(at 0 0.4445 270)
			(size 0.1397 0.1397)
			(layers "F.Cu" "F.Mask" "F.Paste")
			(net "SW_HDD_P31")
			(options
				(clearance outline)
				(anchor circle)
			)
			(primitives
				(gr_poly
					(pts
						(arc
							(start -0.1778 -0.2794)
							(mid -0.249642 -0.249642)
							(end -0.2794 -0.1778)
						)
						(arc
							(start -0.2794 0.1778)
							(mid -0.249642 0.249642)
							(end -0.1778 0.2794)
						)
						(arc
							(start 0.1778 0.2794)
							(mid 0.249642 0.249642)
							(end 0.2794 0.1778)
						)
						(arc
							(start 0.2794 -0.1778)
							(mid 0.249642 -0.249642)
							(end 0.1778 -0.2794)
						)
					)
					(width 0)
					(fill yes)
				)
			)
		)
	)
	(footprint ""
		(layer "F.Cu")
		(at 475.361 -148.717 -90)
		(property "Reference" "C329"
			(at 0 0 270)
			(layer "F.SilkS")
			(hide yes)
			(effects
				(font
					(size 1.27 1.27)
				)
			)
		)
		(property "Value" "SC1U16V3KX-5GP"
			(at 0 -2.8194 270)
			(unlocked yes)
			(layer "F.Fab")
			(hide yes)
			(effects
				(font
					(size 1.016 1.016)
					(thickness 0.1524)
				)
			)
		)
		(property "Device Type" "C603H36"
			(at 0 -4.3434 270)
			(unlocked yes)
			(layer "F.Fab")
			(hide yes)
			(effects
				(font
					(size 1.016 1.016)
					(thickness 0.1524)
				)
			)
		)
		(duplicate_pad_numbers_are_jumpers no)
		(fp_line
			(start 0.508 0)
			(end -0.508 0)
			(stroke
				(width 0.2032)
				(type default)
			)
			(layer "F.SilkS")
		)
		(fp_rect
			(start -0.5842 1.3335)
			(end 0.5842 -1.3335)
			(stroke
				(width 0)
				(type default)
			)
			(fill no)
			(layer "F.CrtYd")
		)
		(fp_rect
			(start -0.5842 1.3335)
			(end 0.5842 -1.3335)
			(stroke
				(width 0)
				(type default)
			)
			(fill no)
			(layer "F.Fab")
		)
		(pad "1" smd custom
			(at 0 -0.762 270)
			(size 0.2159 0.2159)
			(layers "F.Cu" "F.Mask" "F.Paste")
			(net "P5V_HDD23")
			(options
				(clearance outline)
				(anchor circle)
			)
			(primitives
				(gr_poly
					(pts
						(arc
							(start -0.3302 -0.4318)
							(mid -0.402042 -0.402042)
							(end -0.4318 -0.3302)
						)
						(arc
							(start -0.4318 0.3302)
							(mid -0.402042 0.402042)
							(end -0.3302 0.4318)
						)
						(arc
							(start 0.3302 0.4318)
							(mid 0.402042 0.402042)
							(end 0.4318 0.3302)
						)
						(arc
							(start 0.4318 -0.3302)
							(mid 0.402042 -0.402042)
							(end 0.3302 -0.4318)
						)
					)
					(width 0)
					(fill yes)
				)
			)
		)
		(pad "2" smd custom
			(at 0 0.762 270)
			(size 0.2159 0.2159)
			(layers "F.Cu" "F.Mask" "F.Paste")
			(net "GND")
			(options
				(clearance outline)
				(anchor circle)
			)
			(primitives
				(gr_poly
					(pts
						(arc
							(start -0.3302 -0.4318)
							(mid -0.402042 -0.402042)
							(end -0.4318 -0.3302)
						)
						(arc
							(start -0.4318 0.3302)
							(mid -0.402042 0.402042)
							(end -0.3302 0.4318)
						)
						(arc
							(start 0.3302 0.4318)
							(mid 0.402042 0.402042)
							(end 0.4318 0.3302)
						)
						(arc
							(start 0.4318 -0.3302)
							(mid 0.402042 -0.402042)
							(end 0.3302 -0.4318)
						)
					)
					(width 0)
					(fill yes)
				)
			)
		)
	)
	(footprint ""
		(layer "F.Cu")
		(at 207.89138 -235.18622)
		(property "Reference" "R41"
			(at 0 0 0)
			(layer "F.SilkS")
			(hide yes)
			(effects
				(font
					(size 1.27 1.27)
				)
			)
		)
		(property "Value" "4K7R2F-GP"
			(at 0.064008 -3.993896 0)
			(unlocked yes)
			(layer "F.Fab")
			(hide yes)
			(effects
				(font
					(size 1.016 1.016)
					(thickness 0.1524)
				)
			)
		)
		(property "Device Type" "R402H16"
			(at 0.064008 -5.517896 0)
			(unlocked yes)
			(layer "F.Fab")
			(hide yes)
			(effects
				(font
					(size 1.016 1.016)
					(thickness 0.1524)
				)
			)
		)
		(duplicate_pad_numbers_are_jumpers no)
		(fp_line
			(start -0.508 -0.9398)
			(end -0.508 0.9398)
			(stroke
				(width 0.1524)
				(type default)
			)
			(layer "F.SilkS")
		)
		(fp_line
			(start 0.508 -0.9398)
			(end -0.508 -0.9398)
			(stroke
				(width 0.1524)
				(type default)
			)
			(layer "F.SilkS")
		)
		(fp_rect
			(start -0.508 0.9398)
			(end 0.508 -0.9398)
			(stroke
				(width 0)
				(type default)
			)
			(fill no)
			(layer "F.CrtYd")
		)
		(fp_rect
			(start -0.508 0.9398)
			(end 0.508 -0.9398)
			(stroke
				(width 0)
				(type default)
			)
			(fill no)
			(layer "F.Fab")
		)
		(pad "1" smd custom
			(at 0 -0.4445)
			(size 0.1397 0.1397)
			(layers "F.Cu" "F.Mask" "F.Paste")
			(net "IO_EXP4_A0")
			(options
				(clearance outline)
				(anchor circle)
			)
			(primitives
				(gr_poly
					(pts
						(arc
							(start -0.1778 -0.2794)
							(mid -0.249642 -0.249642)
							(end -0.2794 -0.1778)
						)
						(arc
							(start -0.2794 0.1778)
							(mid -0.249642 0.249642)
							(end -0.1778 0.2794)
						)
						(arc
							(start 0.1778 0.2794)
							(mid 0.249642 0.249642)
							(end 0.2794 0.1778)
						)
						(arc
							(start 0.2794 -0.1778)
							(mid 0.249642 -0.249642)
							(end 0.1778 -0.2794)
						)
					)
					(width 0)
					(fill yes)
				)
			)
		)
		(pad "2" smd custom
			(at 0 0.4445)
			(size 0.1397 0.1397)
			(layers "F.Cu" "F.Mask" "F.Paste")
			(net "GND")
			(options
				(clearance outline)
				(anchor circle)
			)
			(primitives
				(gr_poly
					(pts
						(arc
							(start -0.1778 -0.2794)
							(mid -0.249642 -0.249642)
							(end -0.2794 -0.1778)
						)
						(arc
							(start -0.2794 0.1778)
							(mid -0.249642 0.249642)
							(end -0.1778 0.2794)
						)
						(arc
							(start 0.1778 0.2794)
							(mid 0.249642 0.249642)
							(end 0.2794 0.1778)
						)
						(arc
							(start 0.2794 -0.1778)
							(mid 0.249642 -0.249642)
							(end 0.1778 -0.2794)
						)
					)
					(width 0)
					(fill yes)
				)
			)
		)
	)
	(footprint ""
		(layer "F.Cu")
		(at 129.286 -373.507 90)
		(property "Reference" "R934"
			(at 0 0 90)
			(layer "F.SilkS")
			(hide yes)
			(effects
				(font
					(size 1.27 1.27)
				)
			)
		)
		(property "Value" "4K7R2F-GP"
			(at 0.064008 -3.993896 90)
			(unlocked yes)
			(layer "F.Fab")
			(hide yes)
			(effects
				(font
					(size 1.016 1.016)
					(thickness 0.1524)
				)
			)
		)
		(property "Device Type" "R402H16"
			(at 0.064008 -5.517896 90)
			(unlocked yes)
			(layer "F.Fab")
			(hide yes)
			(effects
				(font
					(size 1.016 1.016)
					(thickness 0.1524)
				)
			)
		)
		(duplicate_pad_numbers_are_jumpers no)
		(fp_line
			(start 0.508 -0.9398)
			(end -0.508 -0.9398)
			(stroke
				(width 0.1524)
				(type default)
			)
			(layer "F.SilkS")
		)
		(fp_line
			(start -0.508 -0.9398)
			(end -0.508 0.9398)
			(stroke
				(width 0.1524)
				(type default)
			)
			(layer "F.SilkS")
		)
		(fp_rect
			(start -0.508 0.9398)
			(end 0.508 -0.9398)
			(stroke
				(width 0)
				(type default)
			)
			(fill no)
			(layer "F.CrtYd")
		)
		(fp_rect
			(start -0.508 0.9398)
			(end 0.508 -0.9398)
			(stroke
				(width 0)
				(type default)
			)
			(fill no)
			(layer "F.Fab")
		)
		(pad "1" smd custom
			(at 0 -0.4445 90)
			(size 0.1397 0.1397)
			(layers "F.Cu" "F.Mask" "F.Paste")
			(net "P12V_IN")
			(options
				(clearance outline)
				(anchor circle)
			)
			(primitives
				(gr_poly
					(pts
						(arc
							(start -0.1778 -0.2794)
							(mid -0.249642 -0.249642)
							(end -0.2794 -0.1778)
						)
						(arc
							(start -0.2794 0.1778)
							(mid -0.249642 0.249642)
							(end -0.1778 0.2794)
						)
						(arc
							(start 0.1778 0.2794)
							(mid 0.249642 0.249642)
							(end 0.2794 0.1778)
						)
						(arc
							(start 0.2794 -0.1778)
							(mid 0.249642 -0.249642)
							(end 0.1778 -0.2794)
						)
					)
					(width 0)
					(fill yes)
				)
			)
		)
		(pad "2" smd custom
			(at 0 0.4445 90)
			(size 0.1397 0.1397)
			(layers "F.Cu" "F.Mask" "F.Paste")
			(net "FAN_1_TACH0")
			(options
				(clearance outline)
				(anchor circle)
			)
			(primitives
				(gr_poly
					(pts
						(arc
							(start -0.1778 -0.2794)
							(mid -0.249642 -0.249642)
							(end -0.2794 -0.1778)
						)
						(arc
							(start -0.2794 0.1778)
							(mid -0.249642 0.249642)
							(end -0.1778 0.2794)
						)
						(arc
							(start 0.1778 0.2794)
							(mid 0.249642 0.249642)
							(end 0.2794 0.1778)
						)
						(arc
							(start 0.2794 -0.1778)
							(mid 0.249642 -0.249642)
							(end 0.1778 -0.2794)
						)
					)
					(width 0)
					(fill yes)
				)
			)
		)
	)
)
